# T6G (Grand Teton) — schematic netlist excerpt (pin names and nets, part order shuffled) for the footprints in the layout excerpt that follows; sources: Cadence DE-HDL packaged netlist, KiCad conversion of 04192023_DAF0TMB3IC0_F0TG_MB_C_brd_V02_OCP.brd

R1276  Q_RES  0 5% CHIP  pkg 0402LF  page 357 : A = SMB_INA230_6_3V3AUX_SDA_R ; B = SMB_INA230_6_3V3AUX_SDA_R1
C691  Q_CAP_DIFFBUS  DIFF BUS_0.22UF 6.3V 20% X6S  pkg C0201  page 67 : \1\ = P5E_CPU1_G1_TX_C_DP<9> ; \2\ = P5E_CPU1_G1_TX_DP<9>
C1537  Q_CAP_DIFFBUS  DIFF BUS_0.22UF 6.3V 20% X6S  pkg C0201  page 67 : \1\ = P5E_CPU1_P3_TX_C_DP<5> ; \2\ = P5E_CPU1_P3_TX_DP<5>
R1381  Q_RES  4.7K 5% CHIP  pkg 0201LF  page 320 : A = JTAG_TCK_RT_CPU1_P0 ; B = GND
C922  Q_CAP_DIFFBUS  DIFF BUS_0.22UF 6.3V 20% X6S  pkg C0201  page 63 : \1\ = P5E_CPU0_P0_TX_C_DN<5> ; \2\ = P5E_CPU0_P0_TX_DN<5>

(kicad_pcb
	(version 20260206)
	(generator "pcbnew")
	(generator_version "10.0")
	(general
		(thickness 1.6)
		(legacy_teardrops no)
	)
	(paper "A4")
	(title_block
		(title "04192023_DAF0TMB3IC0_F0TG_MB_C_brd_V02_OCP.brd")
		(comment 1 "Grand Teton / footprints 2839-2843 of 8354")
	)
	(layers
		(0 "F.Cu" signal "TOP")
		(4 "In1.Cu" signal "GND")
		(6 "In2.Cu" signal "IN1")
		(8 "In3.Cu" signal "GND1")
		(10 "In4.Cu" signal "IN2")
		(12 "In5.Cu" signal "GND2")
		(14 "In6.Cu" signal "IN3")
		(16 "In7.Cu" signal "GND3")
		(18 "In8.Cu" signal "VCC")
		(20 "In9.Cu" signal "VCC1")
		(22 "In10.Cu" signal "GND4")
		(24 "In11.Cu" signal "IN4")
		(26 "In12.Cu" signal "GND5")
		(28 "In13.Cu" signal "IN5")
		(30 "In14.Cu" signal "GND6")
		(32 "In15.Cu" signal "IN6")
		(34 "In16.Cu" signal "GND7")
		(2 "B.Cu" signal "BOTTOM")
		(9 "F.Adhes" user "F.Adhesive")
		(11 "B.Adhes" user "B.Adhesive")
		(13 "F.Paste" user "Package Geometry/Pastemask Top")
		(15 "B.Paste" user "Package Geometry/Pastemask Bottom")
		(5 "F.SilkS" user "Ref Des/Silkscreen Top")
		(7 "B.SilkS" user "Ref Des/Silkscreen Bottom")
		(1 "F.Mask" user "Board Geometry/Soldermask Top")
		(3 "B.Mask" user "Board Geometry/Soldermask Bottom")
		(17 "Dwgs.User" user "User.Drawings")
		(19 "Cmts.User" user "User.Comments")
		(21 "Eco1.User" user "User.Eco1")
		(23 "Eco2.User" user "User.Eco2")
		(25 "Edge.Cuts" user "Board Geometry/Outline")
		(27 "Margin" user)
		(31 "F.CrtYd" user "Package Geometry/Place Bound Top")
		(29 "B.CrtYd" user "Package Geometry/Place Bound Bottom")
		(35 "F.Fab" user "Ref Des/Assembly Top")
		(33 "B.Fab" user "Ref Des/Assembly Bottom")
	)
	(footprint ""
		(layer "F.Cu")
		(at 47.608744 -421.326564)
		(property "Reference" "R1381"
			(at 0 0 0)
			(layer "F.SilkS")
			(hide yes)
			(effects
				(font
					(size 1.27 1.27)
				)
			)
		)
		(property "Value" ""
			(at 0 0 0)
			(layer "F.Fab")
			(effects
				(font
					(size 1.27 1.27)
				)
			)
		)
		(duplicate_pad_numbers_are_jumpers no)
		(fp_line
			(start -0.32512 -0.175006)
			(end 0.32512 -0.175006)
			(stroke
				(width 0.1)
				(type default)
			)
			(layer "F.Fab")
		)
		(fp_line
			(start -0.32512 0.175006)
			(end -0.32512 -0.175006)
			(stroke
				(width 0.1)
				(type default)
			)
			(layer "F.Fab")
		)
		(fp_line
			(start 0.32512 -0.175006)
			(end 0.32512 0.175006)
			(stroke
				(width 0.1)
				(type default)
			)
			(layer "F.Fab")
		)
		(fp_line
			(start 0.32512 0.175006)
			(end -0.32512 0.175006)
			(stroke
				(width 0.1)
				(type default)
			)
			(layer "F.Fab")
		)
		(pad "1" smd rect
			(at -0.2667 0)
			(size 0.3048 0.381)
			(layers "F.Cu" "F.Mask" "F.Paste")
			(net "JTAG_TCK_RT_CPU1_P0")
		)
		(pad "2" smd rect
			(at 0.2667 0 180)
			(size 0.3048 0.381)
			(layers "F.Cu" "F.Mask" "F.Paste")
			(net "GND")
		)
	)
	(footprint ""
		(layer "F.Cu")
		(at 116.896896 -373.03583 -90)
		(property "Reference" "C1537"
			(at 0 0 270)
			(layer "F.SilkS")
			(hide yes)
			(effects
				(font
					(size 1.27 1.27)
				)
			)
		)
		(property "Value" ""
			(at 0 0 270)
			(layer "F.Fab")
			(effects
				(font
					(size 1.27 1.27)
				)
			)
		)
		(duplicate_pad_numbers_are_jumpers no)
		(fp_line
			(start -0.299974 0.150114)
			(end -0.299974 -0.150114)
			(stroke
				(width 0.1)
				(type default)
			)
			(layer "F.Fab")
		)
		(fp_line
			(start 0.299974 0.150114)
			(end -0.299974 0.150114)
			(stroke
				(width 0.1)
				(type default)
			)
			(layer "F.Fab")
		)
		(fp_line
			(start -0.299974 -0.150114)
			(end 0.299974 -0.150114)
			(stroke
				(width 0.1)
				(type default)
			)
			(layer "F.Fab")
		)
		(fp_line
			(start 0.299974 -0.150114)
			(end 0.299974 0.150114)
			(stroke
				(width 0.1)
				(type default)
			)
			(layer "F.Fab")
		)
		(pad "1" smd rect
			(at -0.2667 0 270)
			(size 0.3048 0.381)
			(layers "F.Cu" "F.Mask" "F.Paste")
			(net "P5E_CPU1_P3_TX_C_DP<5>")
		)
		(pad "2" smd rect
			(at 0.2667 0 270)
			(size 0.3048 0.381)
			(layers "F.Cu" "F.Mask" "F.Paste")
			(net "P5E_CPU1_P3_TX_DP<5>")
		)
	)
	(footprint ""
		(layer "F.Cu")
		(at 306.711096 -381.41783 -90)
		(property "Reference" "C922"
			(at 0 0 270)
			(layer "F.SilkS")
			(hide yes)
			(effects
				(font
					(size 1.27 1.27)
				)
			)
		)
		(property "Value" ""
			(at 0 0 270)
			(layer "F.Fab")
			(effects
				(font
					(size 1.27 1.27)
				)
			)
		)
		(duplicate_pad_numbers_are_jumpers no)
		(fp_line
			(start -0.299974 0.150114)
			(end -0.299974 -0.150114)
			(stroke
				(width 0.1)
				(type default)
			)
			(layer "F.Fab")
		)
		(fp_line
			(start 0.299974 0.150114)
			(end -0.299974 0.150114)
			(stroke
				(width 0.1)
				(type default)
			)
			(layer "F.Fab")
		)
		(fp_line
			(start -0.299974 -0.150114)
			(end 0.299974 -0.150114)
			(stroke
				(width 0.1)
				(type default)
			)
			(layer "F.Fab")
		)
		(fp_line
			(start 0.299974 -0.150114)
			(end 0.299974 0.150114)
			(stroke
				(width 0.1)
				(type default)
			)
			(layer "F.Fab")
		)
		(pad "1" smd rect
			(at -0.2667 0 270)
			(size 0.3048 0.381)
			(layers "F.Cu" "F.Mask" "F.Paste")
			(net "P5E_CPU0_P0_TX_C_DN<5>")
		)
		(pad "2" smd rect
			(at 0.2667 0 270)
			(size 0.3048 0.381)
			(layers "F.Cu" "F.Mask" "F.Paste")
			(net "P5E_CPU0_P0_TX_DN<5>")
		)
	)
	(footprint ""
		(layer "F.Cu")
		(at 33.186878 -16.099536 90)
		(property "Reference" "C691"
			(at 0 0 90)
			(layer "F.SilkS")
			(hide yes)
			(effects
				(font
					(size 1.27 1.27)
				)
			)
		)
		(property "Value" ""
			(at 0 0 90)
			(layer "F.Fab")
			(effects
				(font
					(size 1.27 1.27)
				)
			)
		)
		(duplicate_pad_numbers_are_jumpers no)
		(fp_line
			(start 0.299974 -0.150114)
			(end 0.299974 0.150114)
			(stroke
				(width 0.1)
				(type default)
			)
			(layer "F.Fab")
		)
		(fp_line
			(start -0.299974 -0.150114)
			(end 0.299974 -0.150114)
			(stroke
				(width 0.1)
				(type default)
			)
			(layer "F.Fab")
		)
		(fp_line
			(start 0.299974 0.150114)
			(end -0.299974 0.150114)
			(stroke
				(width 0.1)
				(type default)
			)
			(layer "F.Fab")
		)
		(fp_line
			(start -0.299974 0.150114)
			(end -0.299974 -0.150114)
			(stroke
				(width 0.1)
				(type default)
			)
			(layer "F.Fab")
		)
		(pad "1" smd rect
			(at -0.2667 0 90)
			(size 0.3048 0.381)
			(layers "F.Cu" "F.Mask" "F.Paste")
			(net "P5E_CPU1_G1_TX_C_DP<9>")
		)
		(pad "2" smd rect
			(at 0.2667 0 90)
			(size 0.3048 0.381)
			(layers "F.Cu" "F.Mask" "F.Paste")
			(net "P5E_CPU1_G1_TX_DP<9>")
		)
	)
	(footprint ""
		(layer "F.Cu")
		(at 393.284456 -72.28205)
		(property "Reference" "R1276"
			(at 0 0 0)
			(layer "F.SilkS")
			(hide yes)
			(effects
				(font
					(size 1.27 1.27)
				)
			)
		)
		(property "Value" ""
			(at 0 0 0)
			(layer "F.Fab")
			(effects
				(font
					(size 1.27 1.27)
				)
			)
		)
		(duplicate_pad_numbers_are_jumpers no)
		(fp_line
			(start -0.7874 -0.4064)
			(end 0.7874 -0.4064)
			(stroke
				(width 0.1524)
				(type default)
			)
			(layer "F.SilkS")
		)
		(fp_line
			(start -0.7874 0.4064)
			(end -0.7874 -0.4064)
			(stroke
				(width 0.1524)
				(type default)
			)
			(layer "F.SilkS")
		)
		(fp_line
			(start 0.7874 -0.4064)
			(end 0.7874 0.4064)
			(stroke
				(width 0.1524)
				(type default)
			)
			(layer "F.SilkS")
		)
		(fp_line
			(start 0.7874 0.4064)
			(end -0.7874 0.4064)
			(stroke
				(width 0.1524)
				(type default)
			)
			(layer "F.SilkS")
		)
		(fp_line
			(start -0.67945 -0.305054)
			(end -0.12065 -0.305054)
			(stroke
				(width 0.1)
				(type default)
			)
			(layer "F.Fab")
		)
		(fp_line
			(start -0.67945 0.3048)
			(end -0.67945 -0.305054)
			(stroke
				(width 0.1)
				(type default)
			)
			(layer "F.Fab")
		)
		(fp_line
			(start -0.12065 -0.305054)
			(end -0.12065 -0.2794)
			(stroke
				(width 0.1)
				(type default)
			)
			(layer "F.Fab")
		)
		(fp_line
			(start -0.12065 -0.2794)
			(end 0.12065 -0.2794)
			(stroke
				(width 0.1)
				(type default)
			)
			(layer "F.Fab")
		)
		(fp_line
			(start -0.12065 0.2794)
			(end -0.12065 0.3048)
			(stroke
				(width 0.1)
				(type default)
			)
			(layer "F.Fab")
		)
		(fp_line
			(start -0.12065 0.3048)
			(end -0.67945 0.3048)
			(stroke
				(width 0.1)
				(type default)
			)
			(layer "F.Fab")
		)
		(fp_line
			(start 0.120396 0.2794)
			(end -0.12065 0.2794)
			(stroke
				(width 0.1)
				(type default)
			)
			(layer "F.Fab")
		)
		(fp_line
			(start 0.120396 0.3048)
			(end 0.120396 0.2794)
			(stroke
				(width 0.1)
				(type default)
			)
			(layer "F.Fab")
		)
		(fp_line
			(start 0.12065 -0.3048)
			(end 0.67945 -0.3048)
			(stroke
				(width 0.1)
				(type default)
			)
			(layer "F.Fab")
		)
		(fp_line
			(start 0.12065 -0.2794)
			(end 0.12065 -0.3048)
			(stroke
				(width 0.1)
				(type default)
			)
			(layer "F.Fab")
		)
		(fp_line
			(start 0.67945 -0.3048)
			(end 0.67945 0.3048)
			(stroke
				(width 0.1)
				(type default)
			)
			(layer "F.Fab")
		)
		(fp_line
			(start 0.67945 0.3048)
			(end 0.120396 0.3048)
			(stroke
				(width 0.1)
				(type default)
			)
			(layer "F.Fab")
		)
		(pad "1" smd circle
			(at -0.40005 0)
			(size 0 0)
			(layers "F.Cu" "F.Mask" "F.Paste")
			(net "SMB_INA230_6_3V3AUX_SDA_R")
		)
		(pad "2" smd circle
			(at 0.40005 0)
			(size 0 0)
			(layers "F.Cu" "F.Mask" "F.Paste")
			(net "SMB_INA230_6_3V3AUX_SDA_R1")
		)
	)
)
